FILE_TYPE = MACRO_DRAWING;
SET COLOR_WIRE YELLOW;
SET COLOR_PROP ORANGE;
SET COLOR_DOT WHITE;
SET COLOR_ARC YELLOW;
SET COLOR_BODY GREEN;
SET COLOR_NOTE PURPLE;
SET PROP_DISPLAY VALUE;
SET PAGE_NUMBER P45;
SET PATH_NUMBER P56;
FORCEADD OFFPAGE..1
(-2900 1900);
FORCEPROP 2 LAST $XR0 44 
J 0
(-3121 1900);
DISPLAY 0.638298 (-3121 1900);
PAINT MONO (-3121 1900);
FORCEPROP 2 LAST CDS_LIB standard
J 0
(-2900 1900);
DISPLAY INVISIBLE (-2900 1900);
FORCEPROP 1 LAST OFFPAGE TRUE
J 0
(-2575 1775);
DISPLAY 0.872340 (-2575 1775);
PAINT GREEN (-2575 1775);
DISPLAY INVISIBLE (-2575 1775);
FORCEPROP 1 LAST COMMENT_BODY TRUE
J 0
(-2775 1800);
DISPLAY 0.872340 (-2775 1800);
PAINT PEACH (-2775 1800);
DISPLAY INVISIBLE (-2775 1800);
FORCEPROP 2 LAST PATH I1
J 0
(-3100 1950);
DISPLAY 1.021277 (-3100 1950);
DISPLAY INVISIBLE (-3100 1950);
FORCEADD Q_RES..1
(-1575 1850);
FORCEPROP 1 LAST MATERIAL CHIP
J 0
(-1300 1850);
DISPLAY 0.510638 (-1300 1850);
PAINT SKYBLUE (-1300 1850);
FORCEPROP 1 LAST VALUE 33.2
J 0
(-1425 1850);
DISPLAY 0.510638 (-1425 1850);
PAINT SKYBLUE (-1425 1850);
FORCEPROP 1 LAST TOLERANCE 1%
J 0
(-1450 1850);
DISPLAY 0.510638 (-1450 1850);
PAINT SKYBLUE (-1450 1850);
DISPLAY INVISIBLE (-1450 1850);
FORCEPROP 1 LAST PART_NUMBER CS03322FB03
J 0
(-1625 1950);
DISPLAY 0.510638 (-1625 1950);
PAINT WHITE (-1625 1950);
DISPLAY INVISIBLE (-1625 1950);
FORCEPROP 1 LAST PACK_TYPE 0402LF
J 0
(-1325 1700);
DISPLAY 0.510638 (-1325 1700);
PAINT SKYBLUE (-1325 1700);
DISPLAY INVISIBLE (-1325 1700);
FORCEPROP 1 LAST WATTAGE 1/16W
J 2
(-1600 1700);
DISPLAY 0.510638 (-1600 1700);
PAINT SKYBLUE (-1600 1700);
DISPLAY INVISIBLE (-1600 1700);
FORCEPROP 1 LAST PATH I19
J 0
(-1625 2000);
DISPLAY 0.978723 (-1625 2000);
PAINT WHITE (-1625 2000);
DISPLAY INVISIBLE (-1625 2000);
FORCEPROP 2 LAST CDS_LIB pure_quanta
J 0
(-1575 1850);
DISPLAY INVISIBLE (-1575 1850);
FORCEPROP 1 LAST LOCATION R486
J 0
(-1900 1850);
DISPLAY 0.702128 (-1900 1850);
PAINT YELLOW (-1900 1850);
FORCEPROP 0 LAST $SEC 1
J 0
(-1750 1900);
DISPLAY INVISIBLE (-1750 1900);
FORCEPROP 0 LAST CDS_SEC 1
J 0
(-1750 1900);
DISPLAY INVISIBLE (-1750 1900);
FORCEPROP 1 LASTPIN (-1675 1850) $PN 1
J 0
(-1663 1862);
DISPLAY 0.808511 (-1663 1862);
PAINT WHITE (-1663 1862);
DISPLAY INVISIBLE (-1663 1862);
FORCEPROP 1 LASTPIN (-1475 1850) $PN 2
J 0
(-1513 1862);
DISPLAY 0.808511 (-1513 1862);
PAINT WHITE (-1513 1862);
DISPLAY INVISIBLE (-1513 1862);
FORCEADD OFFPAGE..1
(-2900 2100);
FORCEPROP 2 LAST $XR0 44 
J 0
(-3121 2100);
DISPLAY 0.638298 (-3121 2100);
PAINT MONO (-3121 2100);
FORCEPROP 2 LAST CDS_LIB standard
J 0
(-2900 2100);
DISPLAY INVISIBLE (-2900 2100);
FORCEPROP 1 LAST OFFPAGE TRUE
J 0
(-2575 1975);
DISPLAY 0.872340 (-2575 1975);
PAINT GREEN (-2575 1975);
DISPLAY INVISIBLE (-2575 1975);
FORCEPROP 1 LAST COMMENT_BODY TRUE
J 0
(-2775 2000);
DISPLAY 0.872340 (-2775 2000);
PAINT PEACH (-2775 2000);
DISPLAY INVISIBLE (-2775 2000);
FORCEPROP 2 LAST PATH I2
J 0
(-3100 2150);
DISPLAY 1.021277 (-3100 2150);
DISPLAY INVISIBLE (-3100 2150);
FORCEADD Q_RES..1
(-1575 1900);
FORCEPROP 1 LAST VALUE 33.2
J 0
(-1425 1900);
DISPLAY 0.510638 (-1425 1900);
PAINT SKYBLUE (-1425 1900);
FORCEPROP 1 LAST MATERIAL CHIP
J 0
(-1300 1900);
DISPLAY 0.510638 (-1300 1900);
PAINT SKYBLUE (-1300 1900);
FORCEPROP 1 LAST TOLERANCE 1%
J 0
(-1450 1900);
DISPLAY 0.510638 (-1450 1900);
PAINT SKYBLUE (-1450 1900);
DISPLAY INVISIBLE (-1450 1900);
FORCEPROP 1 LAST PART_NUMBER CS03322FB03
J 0
(-1625 2000);
DISPLAY 0.510638 (-1625 2000);
PAINT WHITE (-1625 2000);
DISPLAY INVISIBLE (-1625 2000);
FORCEPROP 1 LAST PACK_TYPE 0402LF
J 0
(-1325 1750);
DISPLAY 0.510638 (-1325 1750);
PAINT SKYBLUE (-1325 1750);
DISPLAY INVISIBLE (-1325 1750);
FORCEPROP 1 LAST WATTAGE 1/16W
J 2
(-1600 1750);
DISPLAY 0.510638 (-1600 1750);
PAINT SKYBLUE (-1600 1750);
DISPLAY INVISIBLE (-1600 1750);
FORCEPROP 1 LAST PATH I20
J 0
(-1625 2050);
DISPLAY 0.978723 (-1625 2050);
PAINT WHITE (-1625 2050);
DISPLAY INVISIBLE (-1625 2050);
FORCEPROP 2 LAST CDS_LIB pure_quanta
J 0
(-1575 1900);
DISPLAY INVISIBLE (-1575 1900);
FORCEPROP 1 LAST LOCATION R485
J 0
(-1900 1900);
DISPLAY 0.702128 (-1900 1900);
PAINT YELLOW (-1900 1900);
FORCEPROP 0 LAST $SEC 1
J 0
(-1750 1950);
DISPLAY INVISIBLE (-1750 1950);
FORCEPROP 0 LAST CDS_SEC 1
J 0
(-1750 1950);
DISPLAY INVISIBLE (-1750 1950);
FORCEPROP 1 LASTPIN (-1675 1900) $PN 1
J 0
(-1663 1912);
DISPLAY 0.808511 (-1663 1912);
PAINT WHITE (-1663 1912);
DISPLAY INVISIBLE (-1663 1912);
FORCEPROP 1 LASTPIN (-1475 1900) $PN 2
J 0
(-1513 1912);
DISPLAY 0.808511 (-1513 1912);
PAINT WHITE (-1513 1912);
DISPLAY INVISIBLE (-1513 1912);
FORCEADD Q_RES..1
(-1575 1950);
FORCEPROP 1 LAST VALUE 33.2
J 0
(-1425 1950);
DISPLAY 0.510638 (-1425 1950);
PAINT SKYBLUE (-1425 1950);
FORCEPROP 1 LAST MATERIAL CHIP
J 0
(-1300 1950);
DISPLAY 0.510638 (-1300 1950);
PAINT SKYBLUE (-1300 1950);
FORCEPROP 1 LAST TOLERANCE 1%
J 0
(-1450 1950);
DISPLAY 0.510638 (-1450 1950);
PAINT SKYBLUE (-1450 1950);
DISPLAY INVISIBLE (-1450 1950);
FORCEPROP 1 LAST PART_NUMBER CS03322FB03
J 0
(-1625 2050);
DISPLAY 0.510638 (-1625 2050);
PAINT WHITE (-1625 2050);
DISPLAY INVISIBLE (-1625 2050);
FORCEPROP 1 LAST PACK_TYPE 0402LF
J 0
(-1325 1800);
DISPLAY 0.510638 (-1325 1800);
PAINT SKYBLUE (-1325 1800);
DISPLAY INVISIBLE (-1325 1800);
FORCEPROP 1 LAST WATTAGE 1/16W
J 2
(-1600 1800);
DISPLAY 0.510638 (-1600 1800);
PAINT SKYBLUE (-1600 1800);
DISPLAY INVISIBLE (-1600 1800);
FORCEPROP 1 LAST PATH I21
J 0
(-1625 2100);
DISPLAY 0.978723 (-1625 2100);
PAINT WHITE (-1625 2100);
DISPLAY INVISIBLE (-1625 2100);
FORCEPROP 2 LAST CDS_LIB pure_quanta
J 0
(-1575 1950);
DISPLAY INVISIBLE (-1575 1950);
FORCEPROP 1 LAST LOCATION R484
J 0
(-1900 1950);
DISPLAY 0.702128 (-1900 1950);
PAINT YELLOW (-1900 1950);
FORCEPROP 0 LAST $SEC 1
J 0
(-1750 2000);
DISPLAY INVISIBLE (-1750 2000);
FORCEPROP 0 LAST CDS_SEC 1
J 0
(-1750 2000);
DISPLAY INVISIBLE (-1750 2000);
FORCEPROP 1 LASTPIN (-1675 1950) $PN 1
J 0
(-1663 1962);
DISPLAY 0.808511 (-1663 1962);
PAINT WHITE (-1663 1962);
DISPLAY INVISIBLE (-1663 1962);
FORCEPROP 1 LASTPIN (-1475 1950) $PN 2
J 0
(-1513 1962);
DISPLAY 0.808511 (-1513 1962);
PAINT WHITE (-1513 1962);
DISPLAY INVISIBLE (-1513 1962);
FORCEADD Q_RES..1
(-1575 2050);
FORCEPROP 1 LAST VALUE 33.2
J 0
(-1425 2050);
DISPLAY 0.510638 (-1425 2050);
PAINT SKYBLUE (-1425 2050);
FORCEPROP 1 LAST MATERIAL CHIP
J 0
(-1300 2050);
DISPLAY 0.510638 (-1300 2050);
PAINT SKYBLUE (-1300 2050);
FORCEPROP 1 LAST TOLERANCE 1%
J 0
(-1450 2050);
DISPLAY 0.510638 (-1450 2050);
PAINT SKYBLUE (-1450 2050);
DISPLAY INVISIBLE (-1450 2050);
FORCEPROP 1 LAST PART_NUMBER CS03322FB03
J 0
(-1625 2150);
DISPLAY 0.510638 (-1625 2150);
PAINT WHITE (-1625 2150);
DISPLAY INVISIBLE (-1625 2150);
FORCEPROP 1 LAST PACK_TYPE 0402LF
J 0
(-1325 1900);
DISPLAY 0.510638 (-1325 1900);
PAINT SKYBLUE (-1325 1900);
DISPLAY INVISIBLE (-1325 1900);
FORCEPROP 1 LAST WATTAGE 1/16W
J 2
(-1600 1900);
DISPLAY 0.510638 (-1600 1900);
PAINT SKYBLUE (-1600 1900);
DISPLAY INVISIBLE (-1600 1900);
FORCEPROP 1 LAST PATH I22
J 0
(-1625 2200);
DISPLAY 0.978723 (-1625 2200);
PAINT WHITE (-1625 2200);
DISPLAY INVISIBLE (-1625 2200);
FORCEPROP 2 LAST CDS_LIB pure_quanta
J 0
(-1575 2050);
DISPLAY INVISIBLE (-1575 2050);
FORCEPROP 1 LAST LOCATION R482
J 0
(-1900 2050);
DISPLAY 0.702128 (-1900 2050);
PAINT YELLOW (-1900 2050);
FORCEPROP 0 LAST $SEC 1
J 0
(-1900 2100);
DISPLAY 0.680851 (-1900 2100);
PAINT MONO (-1900 2100);
DISPLAY INVISIBLE (-1900 2100);
FORCEPROP 0 LAST CDS_SEC 1
J 0
(-1900 2100);
DISPLAY 1.021277 (-1900 2100);
DISPLAY INVISIBLE (-1900 2100);
FORCEPROP 1 LASTPIN (-1675 2050) $PN 1
J 0
(-1663 2062);
DISPLAY 0.808511 (-1663 2062);
PAINT WHITE (-1663 2062);
DISPLAY INVISIBLE (-1663 2062);
FORCEPROP 1 LASTPIN (-1475 2050) $PN 2
J 0
(-1513 2062);
DISPLAY 0.808511 (-1513 2062);
PAINT WHITE (-1513 2062);
DISPLAY INVISIBLE (-1513 2062);
FORCEADD Q_RES..1
(-1575 2000);
FORCEPROP 1 LAST MATERIAL CHIP
J 0
(-1300 2000);
DISPLAY 0.510638 (-1300 2000);
PAINT SKYBLUE (-1300 2000);
FORCEPROP 1 LAST VALUE 33.2
J 0
(-1425 2000);
DISPLAY 0.510638 (-1425 2000);
PAINT SKYBLUE (-1425 2000);
FORCEPROP 1 LAST TOLERANCE 1%
J 0
(-1450 2000);
DISPLAY 0.510638 (-1450 2000);
PAINT SKYBLUE (-1450 2000);
DISPLAY INVISIBLE (-1450 2000);
FORCEPROP 1 LAST PART_NUMBER CS03322FB03
J 0
(-1625 2100);
DISPLAY 0.510638 (-1625 2100);
PAINT WHITE (-1625 2100);
DISPLAY INVISIBLE (-1625 2100);
FORCEPROP 1 LAST PACK_TYPE 0402LF
J 0
(-1325 1850);
DISPLAY 0.510638 (-1325 1850);
PAINT SKYBLUE (-1325 1850);
DISPLAY INVISIBLE (-1325 1850);
FORCEPROP 1 LAST WATTAGE 1/16W
J 2
(-1600 1850);
DISPLAY 0.510638 (-1600 1850);
PAINT SKYBLUE (-1600 1850);
DISPLAY INVISIBLE (-1600 1850);
FORCEPROP 1 LAST PATH I23
J 0
(-1625 2150);
DISPLAY 0.978723 (-1625 2150);
PAINT WHITE (-1625 2150);
DISPLAY INVISIBLE (-1625 2150);
FORCEPROP 2 LAST CDS_LIB pure_quanta
J 0
(-1575 2000);
DISPLAY INVISIBLE (-1575 2000);
FORCEPROP 1 LAST LOCATION R483
J 0
(-1900 2000);
DISPLAY 0.702128 (-1900 2000);
PAINT YELLOW (-1900 2000);
FORCEPROP 0 LAST $SEC 1
J 0
(-1750 2050);
DISPLAY INVISIBLE (-1750 2050);
FORCEPROP 0 LAST CDS_SEC 1
J 0
(-1750 2050);
DISPLAY INVISIBLE (-1750 2050);
FORCEPROP 1 LASTPIN (-1675 2000) $PN 1
J 0
(-1663 2012);
DISPLAY 0.808511 (-1663 2012);
PAINT WHITE (-1663 2012);
DISPLAY INVISIBLE (-1663 2012);
FORCEPROP 1 LASTPIN (-1475 2000) $PN 2
J 0
(-1513 2012);
DISPLAY 0.808511 (-1513 2012);
PAINT WHITE (-1513 2012);
DISPLAY INVISIBLE (-1513 2012);
FORCEADD Q_RES..1
(-1575 2100);
FORCEPROP 1 LAST MATERIAL CHIP
J 0
(-1300 2100);
DISPLAY 0.510638 (-1300 2100);
PAINT SKYBLUE (-1300 2100);
FORCEPROP 1 LAST VALUE 33.2
J 0
(-1425 2100);
DISPLAY 0.510638 (-1425 2100);
PAINT SKYBLUE (-1425 2100);
FORCEPROP 1 LAST TOLERANCE 1%
J 0
(-1450 2100);
DISPLAY 0.510638 (-1450 2100);
PAINT SKYBLUE (-1450 2100);
DISPLAY INVISIBLE (-1450 2100);
FORCEPROP 1 LAST PART_NUMBER CS03322FB03
J 0
(-1625 2200);
DISPLAY 0.510638 (-1625 2200);
PAINT WHITE (-1625 2200);
DISPLAY INVISIBLE (-1625 2200);
FORCEPROP 1 LAST PACK_TYPE 0402LF
J 0
(-1325 1950);
DISPLAY 0.510638 (-1325 1950);
PAINT SKYBLUE (-1325 1950);
DISPLAY INVISIBLE (-1325 1950);
FORCEPROP 1 LAST WATTAGE 1/16W
J 2
(-1600 1950);
DISPLAY 0.510638 (-1600 1950);
PAINT SKYBLUE (-1600 1950);
DISPLAY INVISIBLE (-1600 1950);
FORCEPROP 1 LAST PATH I24
J 0
(-1625 2250);
DISPLAY 0.978723 (-1625 2250);
PAINT WHITE (-1625 2250);
DISPLAY INVISIBLE (-1625 2250);
FORCEPROP 2 LAST CDS_LIB pure_quanta
J 0
(-1575 2100);
DISPLAY INVISIBLE (-1575 2100);
FORCEPROP 1 LAST LOCATION R481
J 0
(-1900 2100);
DISPLAY 0.702128 (-1900 2100);
PAINT YELLOW (-1900 2100);
FORCEPROP 0 LAST $SEC 1
J 0
(-1900 2150);
DISPLAY 0.680851 (-1900 2150);
PAINT MONO (-1900 2150);
DISPLAY INVISIBLE (-1900 2150);
FORCEPROP 0 LAST CDS_SEC 1
J 0
(-1900 2150);
DISPLAY 1.021277 (-1900 2150);
DISPLAY INVISIBLE (-1900 2150);
FORCEPROP 1 LASTPIN (-1675 2100) $PN 1
J 0
(-1663 2112);
DISPLAY 0.808511 (-1663 2112);
PAINT WHITE (-1663 2112);
DISPLAY INVISIBLE (-1663 2112);
FORCEPROP 1 LASTPIN (-1475 2100) $PN 2
J 0
(-1513 2112);
DISPLAY 0.808511 (-1513 2112);
PAINT WHITE (-1513 2112);
DISPLAY INVISIBLE (-1513 2112);
FORCEADD OFFPAGE..3
R 2
(-2875 1950);
FORCEPROP 2 LAST $XR0 44 
J 0
(-3124 1950);
DISPLAY 0.638298 (-3124 1950);
PAINT MONO (-3124 1950);
FORCEPROP 2 LAST CDS_LIB standard
J 0
(-2875 1950);
DISPLAY INVISIBLE (-2875 1950);
FORCEPROP 1 LAST OFFPAGE TRUE
J 2
(-3200 1825);
DISPLAY 0.872340 (-3200 1825);
PAINT GREEN (-3200 1825);
DISPLAY INVISIBLE (-3200 1825);
FORCEPROP 1 LAST COMMENT_BODY TRUE
J 2
(-2825 1850);
DISPLAY 0.872340 (-2825 1850);
PAINT PEACH (-2825 1850);
DISPLAY INVISIBLE (-2825 1850);
FORCEPROP 2 LAST PATH I3
J 0
(-3100 2000);
DISPLAY 1.021277 (-3100 2000);
DISPLAY INVISIBLE (-3100 2000);
FORCEADD Q_RES..2
(-1075 2350);
FORCEPROP 1 LAST VALUE 4.7K
J 0
(-1025 2375);
DISPLAY 0.510638 (-1025 2375);
PAINT SKYBLUE (-1025 2375);
FORCEPROP 1 LAST MATERIAL CHIP
J 0
(-1025 2275);
DISPLAY 0.510638 (-1025 2275);
PAINT SKYBLUE (-1025 2275);
FORCEPROP 1 LAST TOLERANCE 1%
J 0
(-1025 2325);
DISPLAY 0.510638 (-1025 2325);
PAINT SKYBLUE (-1025 2325);
FORCEPROP 1 LAST PART_NUMBER CS24702FB06
J 0
(-1035 2225);
DISPLAY 0.510638 (-1035 2225);
PAINT WHITE (-1035 2225);
DISPLAY INVISIBLE (-1035 2225);
FORCEPROP 1 LAST PACK_TYPE 0402LF
J 0
(-1035 2175);
DISPLAY 0.510638 (-1035 2175);
PAINT SKYBLUE (-1035 2175);
DISPLAY INVISIBLE (-1035 2175);
FORCEPROP 1 LAST WATTAGE 1/16W
J 0
(-1035 2325);
DISPLAY 0.510638 (-1035 2325);
PAINT SKYBLUE (-1035 2325);
DISPLAY INVISIBLE (-1035 2325);
FORCEPROP 1 LAST PATH I33
J 0
(-1025 2525);
DISPLAY 0.978723 (-1025 2525);
PAINT WHITE (-1025 2525);
DISPLAY INVISIBLE (-1025 2525);
FORCEPROP 2 LAST CDS_LIB pure_quanta
J 0
(-1075 2350);
DISPLAY INVISIBLE (-1075 2350);
FORCEPROP 1 LAST LOCATION R488
J 0
(-1025 2425);
DISPLAY 0.702128 (-1025 2425);
PAINT YELLOW (-1025 2425);
FORCEPROP 1 LASTPIN (-1075 2450) $PN 1
J 0
(-1070 2412);
DISPLAY 0.808511 (-1070 2412);
PAINT WHITE (-1070 2412);
FORCEPROP 1 LASTPIN (-1075 2250) $PN 2
J 0
(-1070 2260);
DISPLAY 0.808511 (-1070 2260);
PAINT WHITE (-1070 2260);
FORCEPROP 0 LAST $SEC 1
J 0
(-1025 2525);
DISPLAY 0.680851 (-1025 2525);
PAINT MONO (-1025 2525);
DISPLAY INVISIBLE (-1025 2525);
FORCEPROP 0 LAST CDS_SEC 1
J 0
(-1025 2525);
DISPLAY 0.680851 (-1025 2525);
DISPLAY INVISIBLE (-1025 2525);
FORCEADD Q_RES..2
(-850 2350);
FORCEPROP 1 LAST MATERIAL CHIP
J 0
(-800 2275);
DISPLAY 0.510638 (-800 2275);
PAINT SKYBLUE (-800 2275);
FORCEPROP 1 LAST TOLERANCE 1%
J 0
(-800 2325);
DISPLAY 0.510638 (-800 2325);
PAINT SKYBLUE (-800 2325);
FORCEPROP 1 LAST VALUE 4.7K
J 0
(-800 2375);
DISPLAY 0.510638 (-800 2375);
PAINT SKYBLUE (-800 2375);
FORCEPROP 1 LAST PART_NUMBER CS24702FB06
J 0
(-810 2225);
DISPLAY 0.510638 (-810 2225);
PAINT WHITE (-810 2225);
DISPLAY INVISIBLE (-810 2225);
FORCEPROP 1 LAST PACK_TYPE 0402LF
J 0
(-810 2175);
DISPLAY 0.510638 (-810 2175);
PAINT SKYBLUE (-810 2175);
DISPLAY INVISIBLE (-810 2175);
FORCEPROP 1 LAST WATTAGE 1/16W
J 0
(-810 2325);
DISPLAY 0.510638 (-810 2325);
PAINT SKYBLUE (-810 2325);
DISPLAY INVISIBLE (-810 2325);
FORCEPROP 1 LAST PATH I34
J 0
(-800 2525);
DISPLAY 0.978723 (-800 2525);
PAINT WHITE (-800 2525);
DISPLAY INVISIBLE (-800 2525);
FORCEPROP 2 LAST CDS_LIB pure_quanta
J 0
(-850 2350);
DISPLAY INVISIBLE (-850 2350);
FORCEPROP 1 LAST LOCATION R490
J 0
(-800 2425);
DISPLAY 0.702128 (-800 2425);
PAINT YELLOW (-800 2425);
FORCEPROP 1 LASTPIN (-850 2450) $PN 1
J 0
(-845 2412);
DISPLAY 0.808511 (-845 2412);
PAINT WHITE (-845 2412);
FORCEPROP 1 LASTPIN (-850 2250) $PN 2
J 0
(-845 2260);
DISPLAY 0.808511 (-845 2260);
PAINT WHITE (-845 2260);
FORCEPROP 0 LAST $SEC 1
J 0
(-800 2525);
DISPLAY 0.680851 (-800 2525);
PAINT MONO (-800 2525);
DISPLAY INVISIBLE (-800 2525);
FORCEPROP 0 LAST CDS_SEC 1
J 0
(-800 2525);
DISPLAY 0.680851 (-800 2525);
DISPLAY INVISIBLE (-800 2525);
FORCEADD Q_RES..2
(-625 2350);
FORCEPROP 1 LAST TOLERANCE 1%
J 0
(-575 2325);
DISPLAY 0.510638 (-575 2325);
PAINT SKYBLUE (-575 2325);
FORCEPROP 1 LAST VALUE 4.7K
J 0
(-575 2375);
DISPLAY 0.510638 (-575 2375);
PAINT SKYBLUE (-575 2375);
FORCEPROP 1 LAST MATERIAL CHIP
J 0
(-575 2275);
DISPLAY 0.510638 (-575 2275);
PAINT SKYBLUE (-575 2275);
FORCEPROP 1 LAST PART_NUMBER CS24702FB06
J 0
(-585 2225);
DISPLAY 0.510638 (-585 2225);
PAINT WHITE (-585 2225);
DISPLAY INVISIBLE (-585 2225);
FORCEPROP 1 LAST PACK_TYPE 0402LF
J 0
(-585 2175);
DISPLAY 0.510638 (-585 2175);
PAINT SKYBLUE (-585 2175);
DISPLAY INVISIBLE (-585 2175);
FORCEPROP 1 LAST WATTAGE 1/16W
J 0
(-585 2325);
DISPLAY 0.510638 (-585 2325);
PAINT SKYBLUE (-585 2325);
DISPLAY INVISIBLE (-585 2325);
FORCEPROP 1 LAST PATH I35
J 0
(-575 2525);
DISPLAY 0.978723 (-575 2525);
PAINT WHITE (-575 2525);
DISPLAY INVISIBLE (-575 2525);
FORCEPROP 2 LAST CDS_LIB pure_quanta
J 0
(-625 2350);
DISPLAY INVISIBLE (-625 2350);
FORCEPROP 1 LAST LOCATION R492
J 0
(-575 2425);
DISPLAY 0.702128 (-575 2425);
PAINT YELLOW (-575 2425);
FORCEPROP 1 LASTPIN (-625 2450) $PN 1
J 0
(-620 2412);
DISPLAY 0.808511 (-620 2412);
PAINT WHITE (-620 2412);
FORCEPROP 1 LASTPIN (-625 2250) $PN 2
J 0
(-620 2260);
DISPLAY 0.808511 (-620 2260);
PAINT WHITE (-620 2260);
FORCEPROP 0 LAST $SEC 1
J 0
(-575 2525);
DISPLAY 0.680851 (-575 2525);
PAINT MONO (-575 2525);
DISPLAY INVISIBLE (-575 2525);
FORCEPROP 0 LAST CDS_SEC 1
J 0
(-575 2525);
DISPLAY 0.680851 (-575 2525);
DISPLAY INVISIBLE (-575 2525);
FORCEADD OFFPAGE..3
R 2
(-2875 1850);
FORCEPROP 2 LAST $XR0 44 
J 0
(-3124 1850);
DISPLAY 0.638298 (-3124 1850);
PAINT MONO (-3124 1850);
FORCEPROP 2 LAST CDS_LIB standard
J 0
(-2875 1850);
DISPLAY INVISIBLE (-2875 1850);
FORCEPROP 1 LAST OFFPAGE TRUE
J 2
(-3200 1725);
DISPLAY 0.872340 (-3200 1725);
PAINT GREEN (-3200 1725);
DISPLAY INVISIBLE (-3200 1725);
FORCEPROP 1 LAST COMMENT_BODY TRUE
J 2
(-2825 1750);
DISPLAY 0.872340 (-2825 1750);
PAINT PEACH (-2825 1750);
DISPLAY INVISIBLE (-2825 1750);
FORCEPROP 2 LAST PATH I4
J 0
(-3100 1900);
DISPLAY 1.021277 (-3100 1900);
DISPLAY INVISIBLE (-3100 1900);
FORCEADD UNIVERSAL_GND..1
R 1
(1950 1850);
FORCEPROP 3 LASTPIN (1900 1850) SIG_NAME GND\g
J 0
(1910 1860);
DISPLAY 0.659574 (1910 1860);
PAINT MONO (1910 1860);
DISPLAY INVISIBLE (1910 1860);
FORCEPROP 2 LAST CDS_LIB logical_power
R 1
J 0
(1950 1850);
PAINT MONO (1950 1850);
DISPLAY INVISIBLE (1950 1850);
FORCEPROP 1 LAST PATH I40
R 1
J 0
(1950 1925);
DISPLAY 0.872340 (1950 1925);
PAINT AQUA (1950 1925);
DISPLAY INVISIBLE (1950 1925);
FORCEPROP 1 LAST HDL_POWER GND
R 1
J 1
(2025 1875);
DISPLAY 0.702128 (2025 1875);
PAINT GREEN (2025 1875);
DISPLAY INVISIBLE (2025 1875);
FORCEADD Q_CAP..1
(-800 3025);
FORCEPROP 1 LAST MATERIAL X6S
J 0
(-750 2925);
DISPLAY 0.510638 (-750 2925);
PAINT SKYBLUE (-750 2925);
FORCEPROP 1 LAST VALUE 1UF
J 0
(-750 3075);
DISPLAY 0.510638 (-750 3075);
PAINT SKYBLUE (-750 3075);
FORCEPROP 1 LAST TOLERANCE 10%
J 0
(-750 2975);
DISPLAY 0.510638 (-750 2975);
PAINT SKYBLUE (-750 2975);
FORCEPROP 1 LAST PACK_TYPE C0402
J 0
(-750 2825);
DISPLAY 0.510638 (-750 2825);
PAINT SKYBLUE (-750 2825);
FORCEPROP 1 LAST VOLTAGE 25V
J 0
(-750 3025);
DISPLAY 0.510638 (-750 3025);
PAINT SKYBLUE (-750 3025);
FORCEPROP 1 LAST PART_NUMBER CH5104KEB02
J 0
(-750 2875);
DISPLAY 0.510638 (-750 2875);
PAINT WHITE (-750 2875);
FORCEPROP 2 LAST CDS_LIB pure_quanta
J 0
(-800 3025);
DISPLAY INVISIBLE (-800 3025);
FORCEPROP 1 LAST PATH I42
J 0
(-750 3175);
DISPLAY 0.978723 (-750 3175);
PAINT WHITE (-750 3175);
DISPLAY INVISIBLE (-750 3175);
FORCEPROP 1 LAST LOCATION C244
J 0
(-750 3125);
DISPLAY 0.702128 (-750 3125);
PAINT YELLOW (-750 3125);
FORCEPROP 1 LASTPIN (-800 3125) $PN 1
J 0
(-790 3105);
DISPLAY 0.808511 (-790 3105);
PAINT WHITE (-790 3105);
FORCEPROP 1 LASTPIN (-800 2925) $PN 2
J 0
(-790 2905);
DISPLAY 0.808511 (-790 2905);
PAINT WHITE (-790 2905);
FORCEPROP 2 LAST $SEC 1
J 0
(-750 3225);
DISPLAY 0.680851 (-750 3225);
PAINT MONO (-750 3225);
DISPLAY INVISIBLE (-750 3225);
FORCEPROP 2 LAST CDS_SEC 1
J 0
(-750 3225);
DISPLAY 0.680851 (-750 3225);
DISPLAY INVISIBLE (-750 3225);
FORCEADD UNIVERSAL_GND..1
(-800 2825);
FORCEPROP 3 LASTPIN (-800 2875) SIG_NAME GND\g
J 0
(-790 2885);
DISPLAY 0.659574 (-790 2885);
PAINT MONO (-790 2885);
DISPLAY INVISIBLE (-790 2885);
FORCEPROP 2 LAST CDS_LIB logical_power
J 0
(-800 2825);
DISPLAY INVISIBLE (-800 2825);
FORCEPROP 1 LAST HDL_POWER GND
J 1
(-775 2750);
DISPLAY 0.702128 (-775 2750);
PAINT GREEN (-775 2750);
DISPLAY INVISIBLE (-775 2750);
FORCEPROP 1 LAST PATH I43
J 0
(-725 2825);
DISPLAY 0.872340 (-725 2825);
PAINT AQUA (-725 2825);
DISPLAY INVISIBLE (-725 2825);
FORCEADD UNIVERSAL_GND..1
(-350 2825);
FORCEPROP 3 LASTPIN (-350 2875) SIG_NAME GND\g
J 0
(-340 2885);
DISPLAY 0.659574 (-340 2885);
PAINT MONO (-340 2885);
DISPLAY INVISIBLE (-340 2885);
FORCEPROP 2 LAST CDS_LIB logical_power
J 0
(-350 2825);
DISPLAY INVISIBLE (-350 2825);
FORCEPROP 1 LAST HDL_POWER GND
J 1
(-325 2750);
DISPLAY 0.702128 (-325 2750);
PAINT GREEN (-325 2750);
DISPLAY INVISIBLE (-325 2750);
FORCEPROP 1 LAST PATH I44
J 0
(-275 2825);
DISPLAY 0.872340 (-275 2825);
PAINT AQUA (-275 2825);
DISPLAY INVISIBLE (-275 2825);
FORCEADD Q_CAP..1
(-350 3025);
FORCEPROP 1 LAST MATERIAL X7R
J 0
(-300 2925);
DISPLAY 0.510638 (-300 2925);
PAINT SKYBLUE (-300 2925);
FORCEPROP 1 LAST VALUE 0.01UF
J 0
(-300 3075);
DISPLAY 0.510638 (-300 3075);
PAINT SKYBLUE (-300 3075);
FORCEPROP 1 LAST TOLERANCE 10%
J 0
(-300 2975);
DISPLAY 0.510638 (-300 2975);
PAINT SKYBLUE (-300 2975);
FORCEPROP 1 LAST PACK_TYPE C0402
J 0
(-300 2825);
DISPLAY 0.510638 (-300 2825);
PAINT SKYBLUE (-300 2825);
FORCEPROP 1 LAST PART_NUMBER CH31006KB18
J 0
(-300 2875);
DISPLAY 0.510638 (-300 2875);
PAINT WHITE (-300 2875);
FORCEPROP 1 LAST VOLTAGE 50V
J 0
(-300 3025);
DISPLAY 0.510638 (-300 3025);
PAINT SKYBLUE (-300 3025);
FORCEPROP 2 LAST CDS_LIB pure_quanta
J 0
(-350 3025);
DISPLAY INVISIBLE (-350 3025);
FORCEPROP 1 LAST PATH I45
J 0
(-300 3175);
DISPLAY 0.978723 (-300 3175);
PAINT WHITE (-300 3175);
DISPLAY INVISIBLE (-300 3175);
FORCEPROP 1 LAST LOCATION C246
J 0
(-300 3125);
DISPLAY 0.702128 (-300 3125);
PAINT YELLOW (-300 3125);
FORCEPROP 1 LASTPIN (-350 3125) $PN 1
J 0
(-340 3105);
DISPLAY 0.808511 (-340 3105);
PAINT WHITE (-340 3105);
FORCEPROP 1 LASTPIN (-350 2925) $PN 2
J 0
(-340 2905);
DISPLAY 0.808511 (-340 2905);
PAINT WHITE (-340 2905);
FORCEPROP 2 LAST $SEC 1
J 0
(-300 3225);
DISPLAY 0.680851 (-300 3225);
PAINT MONO (-300 3225);
DISPLAY INVISIBLE (-300 3225);
FORCEPROP 2 LAST CDS_SEC 1
J 0
(-300 3225);
DISPLAY 0.680851 (-300 3225);
DISPLAY INVISIBLE (-300 3225);
FORCEADD UNIVERSAL_POWER..1
(50 3300);
FORCEPROP 3 LASTPIN (50 3250) SIG_NAME P3V3_AUX\g
J 0
(60 3260);
DISPLAY 0.659574 (60 3260);
PAINT MONO (60 3260);
DISPLAY INVISIBLE (60 3260);
FORCEPROP 1 LAST HDL_POWER P3V3_AUX
J 1
(50 3350);
DISPLAY 0.702128 (50 3350);
PAINT GREEN (50 3350);
FORCEPROP 2 LAST CDS_LIB logical_power
J 0
(50 3300);
DISPLAY INVISIBLE (50 3300);
FORCEPROP 1 LAST PATH I46
J 0
(100 3325);
DISPLAY 0.872340 (100 3325);
PAINT AQUA (100 3325);
DISPLAY INVISIBLE (100 3325);
FORCEADD Q_RES..2
R 2
(3275 2250);
FORCEPROP 1 LAST PART_NUMBER CS24702FB06
J 0
(3325 2175);
DISPLAY 0.510638 (3325 2175);
PAINT WHITE (3325 2175);
FORCEPROP 1 LAST TOLERANCE 1%
J 0
(3325 2275);
DISPLAY 0.510638 (3325 2275);
PAINT SKYBLUE (3325 2275);
FORCEPROP 1 LAST VALUE 4.7K
J 0
(3325 2325);
DISPLAY 0.510638 (3325 2325);
PAINT SKYBLUE (3325 2325);
FORCEPROP 1 LAST MATERIAL EMPTY
J 0
(3325 2225);
DISPLAY 0.510638 (3325 2225);
PAINT RED (3325 2225);
FORCEPROP 1 LAST PACK_TYPE 0402LF
J 0
(3325 2125);
DISPLAY 0.510638 (3325 2125);
PAINT SKYBLUE (3325 2125);
FORCEPROP 2 LAST CDS_LIB pure_quanta
J 0
(3275 2250);
DISPLAY INVISIBLE (3275 2250);
FORCEPROP 1 LAST PATH I48
J 2
(3225 2425);
DISPLAY 0.978723 (3225 2425);
PAINT WHITE (3225 2425);
DISPLAY INVISIBLE (3225 2425);
FORCEPROP 1 LAST WATTAGE 1/16W
J 2
(3235 2225);
DISPLAY 0.510638 (3235 2225);
PAINT SKYBLUE (3235 2225);
DISPLAY INVISIBLE (3235 2225);
FORCEPROP 1 LAST LOCATION R496
J 0
(3325 2375);
DISPLAY 0.702128 (3325 2375);
PAINT YELLOW (3325 2375);
FORCEPROP 1 LASTPIN (3275 2350) $PN 1
J 2
(3270 2312);
DISPLAY 0.808511 (3270 2312);
PAINT WHITE (3270 2312);
FORCEPROP 1 LASTPIN (3275 2150) $PN 2
J 2
(3270 2160);
DISPLAY 0.808511 (3270 2160);
PAINT WHITE (3270 2160);
FORCEPROP 0 LAST $SEC 1
J 0
(3250 2425);
DISPLAY 0.680851 (3250 2425);
PAINT MONO (3250 2425);
DISPLAY INVISIBLE (3250 2425);
FORCEPROP 0 LAST CDS_SEC 1
J 0
(3250 2425);
DISPLAY 0.680851 (3250 2425);
DISPLAY INVISIBLE (3250 2425);
FORCEADD UNIVERSAL_POWER..1
(3275 2500);
FORCEPROP 3 LASTPIN (3275 2450) SIG_NAME P3V3_AUX\g
J 0
(3285 2460);
DISPLAY 0.659574 (3285 2460);
PAINT MONO (3285 2460);
DISPLAY INVISIBLE (3285 2460);
FORCEPROP 1 LAST HDL_POWER P3V3_AUX
J 1
(3275 2550);
DISPLAY 0.702128 (3275 2550);
PAINT GREEN (3275 2550);
FORCEPROP 2 LAST CDS_LIB logical_power
J 0
(3275 2500);
DISPLAY INVISIBLE (3275 2500);
FORCEPROP 1 LAST PATH I49
J 0
(3325 2525);
DISPLAY 0.872340 (3325 2525);
PAINT AQUA (3325 2525);
DISPLAY INVISIBLE (3325 2525);
FORCEADD OFFPAGE..3
R 2
(-2875 2050);
FORCEPROP 2 LAST $XR0 44 
J 0
(-3124 2050);
DISPLAY 0.638298 (-3124 2050);
PAINT MONO (-3124 2050);
FORCEPROP 2 LAST CDS_LIB standard
J 0
(-2875 2050);
DISPLAY INVISIBLE (-2875 2050);
FORCEPROP 1 LAST OFFPAGE TRUE
J 2
(-3200 1925);
DISPLAY 0.872340 (-3200 1925);
PAINT GREEN (-3200 1925);
DISPLAY INVISIBLE (-3200 1925);
FORCEPROP 1 LAST COMMENT_BODY TRUE
J 2
(-2825 1950);
DISPLAY 0.872340 (-2825 1950);
PAINT PEACH (-2825 1950);
DISPLAY INVISIBLE (-2825 1950);
FORCEPROP 2 LAST PATH I5
J 0
(-3100 2100);
DISPLAY 1.021277 (-3100 2100);
DISPLAY INVISIBLE (-3100 2100);
FORCEADD Q_RES..2
R 2
(-725 1550);
FORCEPROP 1 LAST PACK_TYPE 0402LF
J 0
(-675 1425);
DISPLAY 0.510638 (-675 1425);
PAINT SKYBLUE (-675 1425);
FORCEPROP 1 LAST PART_NUMBER CS24702FB06
J 0
(-675 1475);
DISPLAY 0.510638 (-675 1475);
PAINT WHITE (-675 1475);
FORCEPROP 1 LAST MATERIAL EMPTY
J 0
(-675 1525);
DISPLAY 0.510638 (-675 1525);
PAINT RED (-675 1525);
FORCEPROP 1 LAST TOLERANCE 1%
J 0
(-675 1575);
DISPLAY 0.510638 (-675 1575);
PAINT SKYBLUE (-675 1575);
FORCEPROP 1 LAST VALUE 4.7K
J 0
(-675 1625);
DISPLAY 0.510638 (-675 1625);
PAINT SKYBLUE (-675 1625);
FORCEPROP 2 LAST CDS_LIB pure_quanta
J 0
(-725 1550);
DISPLAY INVISIBLE (-725 1550);
FORCEPROP 1 LAST PATH I51
J 2
(-775 1725);
DISPLAY 0.978723 (-775 1725);
PAINT WHITE (-775 1725);
DISPLAY INVISIBLE (-775 1725);
FORCEPROP 1 LAST WATTAGE 1/16W
J 2
(-765 1525);
DISPLAY 0.510638 (-765 1525);
PAINT SKYBLUE (-765 1525);
DISPLAY INVISIBLE (-765 1525);
FORCEPROP 1 LAST LOCATION R487
J 0
(-675 1675);
DISPLAY 0.702128 (-675 1675);
PAINT YELLOW (-675 1675);
FORCEPROP 1 LASTPIN (-725 1650) $PN 1
J 2
(-730 1612);
DISPLAY 0.808511 (-730 1612);
PAINT WHITE (-730 1612);
FORCEPROP 1 LASTPIN (-725 1450) $PN 2
J 2
(-730 1460);
DISPLAY 0.808511 (-730 1460);
PAINT WHITE (-730 1460);
FORCEPROP 0 LAST $SEC 1
J 0
(-750 1725);
DISPLAY 0.680851 (-750 1725);
PAINT MONO (-750 1725);
DISPLAY INVISIBLE (-750 1725);
FORCEPROP 0 LAST CDS_SEC 1
J 0
(-750 1725);
DISPLAY 0.680851 (-750 1725);
DISPLAY INVISIBLE (-750 1725);
FORCEADD UNIVERSAL_GND..1
R 2
(-725 1275);
FORCEPROP 3 LASTPIN (-725 1325) SIG_NAME GND\g
J 0
(-715 1335);
DISPLAY 0.659574 (-715 1335);
PAINT MONO (-715 1335);
DISPLAY INVISIBLE (-715 1335);
FORCEPROP 2 LAST CDS_LIB logical_power
R 3
J 0
(-725 1275);
DISPLAY INVISIBLE (-725 1275);
FORCEPROP 1 LAST HDL_POWER GND
J 1
(-750 1200);
DISPLAY 0.702128 (-750 1200);
PAINT GREEN (-750 1200);
DISPLAY INVISIBLE (-750 1200);
FORCEPROP 1 LAST PATH I52
J 2
(-800 1275);
DISPLAY 0.872340 (-800 1275);
PAINT AQUA (-800 1275);
DISPLAY INVISIBLE (-800 1275);
FORCEADD SCONN16_ACASPI006P06..1
(1375 2050);
FORCEPROP 2 LAST PART_TYPE SMLF
J 0
(1025 2625);
DISPLAY 1.021277 (1025 2625);
FORCEPROP 1 LAST MATERIAL IO
J 0
(1025 2375);
DISPLAY 0.723404 (1025 2375);
PAINT GREEN (1025 2375);
FORCEPROP 1 LAST PART_NUMBER DG016000006
J 0
(1025 2450);
DISPLAY 0.723404 (1025 2450);
PAINT GREEN (1025 2450);
FORCEPROP 2 LAST VALUE SCONN16_ACA-SPI-006-P06
J 0
(1025 2575);
DISPLAY 1.021277 (1025 2575);
FORCEPROP 1 LAST PATH I53
J 0
(1375 2050);
DISPLAY 0.723404 (1375 2050);
PAINT GREEN (1375 2050);
DISPLAY INVISIBLE (1375 2050);
FORCEPROP 2 LAST CDS_LIB pure_quanta
J 0
(1375 2050);
DISPLAY INVISIBLE (1375 2050);
FORCEPROP 1 LAST NEEDS_NO_SIZE TRUE
J 0
(1375 2050);
DISPLAY 0.723404 (1375 2050);
PAINT GREEN (1375 2050);
DISPLAY INVISIBLE (1375 2050);
FORCEPROP 1 LAST CDS_LMAN_SYM_OUTLINE -350,300,300,-250
J 0
(1375 2050);
DISPLAY 0.468085 (1375 2050);
PAINT GREEN (1375 2050);
DISPLAY INVISIBLE (1375 2050);
FORCEPROP 1 LAST LOCATION J40
J 0
(1025 2525);
DISPLAY 0.723404 (1025 2525);
PAINT GREEN (1025 2525);
FORCEPROP 0 LASTPIN (875 2100) $PN 16
J 2
(865 2110);
DISPLAY 0.680851 (865 2110);
PAINT MONO (865 2110);
FORCEPROP 0 LASTPIN (875 1900) $PN 7
J 2
(865 1910);
DISPLAY 0.680851 (865 1910);
PAINT MONO (865 1910);
FORCEPROP 0 LASTPIN (875 2050) $PN 15
J 2
(865 2060);
DISPLAY 0.680851 (865 2060);
PAINT MONO (865 2060);
FORCEPROP 0 LASTPIN (875 1950) $PN 8
J 2
(865 1960);
DISPLAY 0.680851 (865 1960);
PAINT MONO (865 1960);
FORCEPROP 0 LASTPIN (1825 1850) $PN 10
J 0
(1835 1860);
DISPLAY 0.680851 (1835 1860);
PAINT MONO (1835 1860);
FORCEPROP 0 LASTPIN (875 1850) $PN 1
J 2
(865 1860);
DISPLAY 0.680851 (865 1860);
PAINT MONO (865 1860);
FORCEPROP 0 LASTPIN (1825 1950) $PN 3
J 0
(1835 1960);
DISPLAY 0.680851 (1835 1960);
PAINT MONO (1835 1960);
FORCEPROP 0 LASTPIN (1825 2000) $PN 4
J 0
(1835 2010);
DISPLAY 0.680851 (1835 2010);
PAINT MONO (1835 2010);
FORCEPROP 0 LASTPIN (1825 2050) $PN 5
J 0
(1835 2060);
DISPLAY 0.680851 (1835 2060);
PAINT MONO (1835 2060);
FORCEPROP 0 LASTPIN (1825 2100) $PN 6
J 0
(1835 2110);
DISPLAY 0.680851 (1835 2110);
PAINT MONO (1835 2110);
FORCEPROP 0 LASTPIN (1825 2150) $PN 11
J 0
(1835 2160);
DISPLAY 0.680851 (1835 2160);
PAINT MONO (1835 2160);
FORCEPROP 0 LASTPIN (1825 2200) $PN 12
J 0
(1835 2210);
DISPLAY 0.680851 (1835 2210);
PAINT MONO (1835 2210);
FORCEPROP 0 LASTPIN (1825 2250) $PN 13
J 0
(1835 2260);
DISPLAY 0.680851 (1835 2260);
PAINT MONO (1835 2260);
FORCEPROP 0 LASTPIN (1825 2300) $PN 14
J 0
(1835 2310);
DISPLAY 0.680851 (1835 2310);
PAINT MONO (1835 2310);
FORCEPROP 0 LASTPIN (875 2250) $PN 2
J 2
(865 2260);
DISPLAY 0.680851 (865 2260);
PAINT MONO (865 2260);
FORCEPROP 0 LASTPIN (875 2000) $PN 9
J 2
(865 2010);
DISPLAY 0.680851 (865 2010);
PAINT MONO (865 2010);
FORCEPROP 0 LAST $SEC 1
J 0
(1025 2675);
DISPLAY 0.680851 (1025 2675);
PAINT MONO (1025 2675);
DISPLAY INVISIBLE (1025 2675);
FORCEPROP 0 LAST CDS_SEC 1
J 0
(1025 2675);
DISPLAY 1.021277 (1025 2675);
DISPLAY INVISIBLE (1025 2675);
FORCEADD MX25L51245GMI10G..1
(1325 750);
FORCEPROP 2 LAST PART_TYPE SMLF
J 0
(1075 1350);
DISPLAY 0.680851 (1075 1350);
FORCEPROP 2 LAST VALUE MX25L51245GMI-10G
J 0
(1075 1300);
DISPLAY 0.680851 (1075 1300);
FORCEPROP 1 LAST PART_NUMBER AKE3FF00Z00
J 0
(1055 1162);
DISPLAY 0.723404 (1055 1162);
PAINT GREEN (1055 1162);
FORCEPROP 1 LAST MATERIAL EMPTY
J 0
(1055 1080);
DISPLAY 0.723404 (1055 1080);
PAINT RED (1055 1080);
FORCEPROP 2 LAST CDS_LIB pure_quanta
J 0
(1325 750);
DISPLAY INVISIBLE (1325 750);
FORCEPROP 1 LAST PATH I54
J 0
(1325 750);
DISPLAY 0.723404 (1325 750);
PAINT GREEN (1325 750);
DISPLAY INVISIBLE (1325 750);
FORCEPROP 1 LAST NEEDS_NO_SIZE TRUE
J 0
(1325 750);
DISPLAY 0.723404 (1325 750);
PAINT GREEN (1325 750);
DISPLAY INVISIBLE (1325 750);
FORCEPROP 1 LAST CDS_LMAN_SYM_OUTLINE -275,325,275,-325
J 0
(1325 750);
DISPLAY 0.468085 (1325 750);
PAINT GREEN (1325 750);
DISPLAY INVISIBLE (1325 750);
FORCEPROP 1 LAST $LOCATION U17
J 0
(1055 1261);
DISPLAY 0.723404 (1055 1261);
PAINT GREEN (1055 1261);
FORCEPROP 0 LASTPIN (900 525) $PN 7
J 2
(890 535);
DISPLAY 0.680851 (890 535);
PAINT MONO (890 535);
FORCEPROP 0 LASTPIN (1750 875) $PN 5
J 0
(1760 885);
DISPLAY 0.680851 (1760 885);
PAINT MONO (1760 885);
FORCEPROP 0 LASTPIN (1750 825) $PN 6
J 0
(1760 835);
DISPLAY 0.680851 (1760 835);
PAINT MONO (1760 835);
FORCEPROP 0 LASTPIN (1750 775) $PN 11
J 0
(1760 785);
DISPLAY 0.680851 (1760 785);
PAINT MONO (1760 785);
FORCEPROP 0 LASTPIN (1750 725) $PN 12
J 0
(1760 735);
DISPLAY 0.680851 (1760 735);
PAINT MONO (1760 735);
FORCEPROP 0 LASTPIN (1750 475) $PN 10
J 0
(1760 485);
DISPLAY 0.680851 (1760 485);
PAINT MONO (1760 485);
FORCEPROP 0 LASTPIN (1750 1025) $PN 4
J 0
(1760 1035);
DISPLAY 0.680851 (1760 1035);
PAINT MONO (1760 1035);
FORCEPROP 0 LASTPIN (1750 975) $PN 13
J 0
(1760 985);
DISPLAY 0.680851 (1760 985);
PAINT MONO (1760 985);
FORCEPROP 0 LASTPIN (1750 925) $PN 14
J 0
(1760 935);
DISPLAY 0.680851 (1760 935);
PAINT MONO (1760 935);
FORCEPROP 0 LASTPIN (900 475) $PN 1
J 2
(890 485);
DISPLAY 0.680851 (890 485);
PAINT MONO (890 485);
FORCEPROP 0 LASTPIN (1750 625) $PN 3
J 0
(1760 635);
DISPLAY 0.680851 (1760 635);
PAINT MONO (1760 635);
FORCEPROP 0 LASTPIN (900 725) $PN 16
J 2
(890 735);
DISPLAY 0.680851 (890 735);
PAINT MONO (890 735);
FORCEPROP 0 LASTPIN (900 675) $PN 15
J 2
(890 685);
DISPLAY 0.680851 (890 685);
PAINT MONO (890 685);
FORCEPROP 0 LASTPIN (900 575) $PN 8
J 2
(890 585);
DISPLAY 0.680851 (890 585);
PAINT MONO (890 585);
FORCEPROP 0 LASTPIN (900 1025) $PN 2
J 2
(890 1035);
DISPLAY 0.680851 (890 1035);
PAINT MONO (890 1035);
FORCEPROP 0 LASTPIN (900 625) $PN 9
J 2
(890 635);
DISPLAY 0.680851 (890 635);
PAINT MONO (890 635);
FORCEPROP 0 LAST CDS_LOCATION U17
J 0
(1075 1400);
DISPLAY 0.680851 (1075 1400);
DISPLAY INVISIBLE (1075 1400);
FORCEPROP 0 LAST $SEC 1
J 0
(1075 1400);
DISPLAY 0.680851 (1075 1400);
PAINT MONO (1075 1400);
DISPLAY INVISIBLE (1075 1400);
FORCEPROP 0 LAST CDS_SEC 1
J 0
(1075 1400);
DISPLAY 0.680851 (1075 1400);
DISPLAY INVISIBLE (1075 1400);
FORCEADD UNIVERSAL_POWER..1
(875 1200);
FORCEPROP 3 LASTPIN (875 1150) SIG_NAME P3V3_AUX\g
J 0
(885 1160);
DISPLAY 0.659574 (885 1160);
PAINT MONO (885 1160);
DISPLAY INVISIBLE (885 1160);
FORCEPROP 1 LAST HDL_POWER P3V3_AUX
J 1
(875 1250);
DISPLAY 0.702128 (875 1250);
PAINT GREEN (875 1250);
FORCEPROP 1 LAST PATH I55
J 0
(925 1225);
DISPLAY 0.872340 (925 1225);
PAINT AQUA (925 1225);
DISPLAY INVISIBLE (925 1225);
FORCEPROP 2 LAST CDS_LIB logical_power
J 0
(875 1200);
DISPLAY INVISIBLE (875 1200);
FORCEADD UNIVERSAL_GND..1
R 1
(1875 475);
FORCEPROP 3 LASTPIN (1825 475) SIG_NAME GND\g
J 0
(1835 485);
DISPLAY 0.659574 (1835 485);
PAINT MONO (1835 485);
DISPLAY INVISIBLE (1835 485);
FORCEPROP 1 LAST HDL_POWER GND
R 1
J 1
(1950 500);
DISPLAY 0.702128 (1950 500);
PAINT GREEN (1950 500);
DISPLAY INVISIBLE (1950 500);
FORCEPROP 1 LAST PATH I56
R 1
J 0
(1875 550);
DISPLAY 0.872340 (1875 550);
PAINT AQUA (1875 550);
DISPLAY INVISIBLE (1875 550);
FORCEPROP 2 LAST CDS_LIB logical_power
J 0
(1875 475);
DISPLAY INVISIBLE (1875 475);
FORCEADD OFFPAGE..3
R 2
(-2875 2000);
FORCEPROP 2 LAST $XR0 44 
J 0
(-3124 2000);
DISPLAY 0.638298 (-3124 2000);
PAINT MONO (-3124 2000);
FORCEPROP 2 LAST CDS_LIB standard
J 0
(-2875 2000);
DISPLAY INVISIBLE (-2875 2000);
FORCEPROP 1 LAST OFFPAGE TRUE
J 2
(-3200 1875);
DISPLAY 0.872340 (-3200 1875);
PAINT GREEN (-3200 1875);
DISPLAY INVISIBLE (-3200 1875);
FORCEPROP 1 LAST COMMENT_BODY TRUE
J 2
(-2825 1900);
DISPLAY 0.872340 (-2825 1900);
PAINT PEACH (-2825 1900);
DISPLAY INVISIBLE (-2825 1900);
FORCEPROP 2 LAST PATH I6
J 0
(-3100 2050);
DISPLAY 1.021277 (-3100 2050);
DISPLAY INVISIBLE (-3100 2050);
FORCEADD QUANTA_TITLE_BLOCK_C..1
(5325 -2375);
FORCEPROP 0 LAST CDS_CON_LAST_MODIFIED Fri Aug 25 17:25:46 2023
J 0
(3440 -2360);
DISPLAY INVISIBLE (3440 -2360);
FORCEPROP 2 LAST Q_DEPT 
J 1
(1562 -2326);
DISPLAY 1.957447 (1562 -2326);
PAINT GREEN (1562 -2326);
FORCEPROP 1 LAST CUSTOM_TXT_CDS <CON_LAST_MODIFIED>
J 0
(3440 -2360);
DISPLAY 0.978723 (3440 -2360);
FORCEPROP 2 LAST CUSTOM_TXT_CDS <XR_PAGE_TITLE>
J 0
(-2565 2875);
DISPLAY 0.638298 (-2565 2875);
PAINT PINK (-2565 2875);
DISPLAY INVISIBLE (-2565 2875);
FORCEPROP 1 LAST CUSTOM_TXT_CDS <NAME_2>
J 0
(2150 -2325);
FORCEPROP 1 LAST CUSTOM_TXT_CDS <NAME_1>
J 0
(2150 -2200);
FORCEPROP 1 LAST CUSTOM_TXT_CDS <Q_NUMBER>
J 0
(3922 -2272);
DISPLAY 1.212766 (3922 -2272);
FORCEPROP 1 LAST CUSTOM_TXT_CDS <Q_PROJ>
J 0
(2943 -2273);
DISPLAY 1.212766 (2943 -2273);
FORCEPROP 1 LAST CUSTOM_TXT_CDS <Q_REV>
J 0
(5141 -2272);
DISPLAY 1.212766 (5141 -2272);
FORCEPROP 1 LAST CUSTOM_TXT_CDS <CON_PAGE_NUM> OF <CON_TOTAL_PAGES>
J 0
(4879 -2357);
DISPLAY 0.978723 (4879 -2357);
FORCEPROP 1 LAST Q_TITLE PCH BIOS ROM
J 0
(-4016 -2349);
DISPLAY 2.446809 (-4016 -2349);
PAINT GREEN (-4016 -2349);
FORCEPROP 2 LAST CDS_XR_PAGE_TITLE CR-45 : @SCM_LIB.SCM(SCH_1):PAGE45
J 0
(-2565 2875);
DISPLAY 0.638298 (-2565 2875);
PAINT PINK (-2565 2875);
DISPLAY INVISIBLE (-2565 2875);
FORCEPROP 1 LAST CDS_LMAN_SYM_OUTLINE -9475,6775,100,-125
J 0
(5325 -2375);
DISPLAY 0.468085 (5325 -2375);
PAINT GREEN (5325 -2375);
DISPLAY INVISIBLE (5325 -2375);
FORCEPROP 2 LAST CDS_LIB pure_quanta
J 0
(5325 -2375);
DISPLAY INVISIBLE (5325 -2375);
FORCEPROP 2 LAST PAGE_BORDER TRUE
J 0
(-2565 2875);
DISPLAY 0.638298 (-2565 2875);
PAINT PINK (-2565 2875);
DISPLAY INVISIBLE (-2565 2875);
FORCEPROP 1 LAST COMMENT_BODY TRUE
J 0
(5337 -2388);
DISPLAY 0.978723 (5337 -2388);
PAINT PEACH (5337 -2388);
DISPLAY INVISIBLE (5337 -2388);
FORCEADD DNS..1
(-700 1550);
PAINT RED (-700 1550);
FORCEPROP 2 LAST CDS_LIB mstr_misc
J 0
(-700 1550);
DISPLAY INVISIBLE (-700 1550);
FORCEPROP 1 LAST COMMENT_BODY TRUE
R 1
J 0
(-625 1325);
DISPLAY 0.872340 (-625 1325);
PAINT PEACH (-625 1325);
DISPLAY INVISIBLE (-625 1325);
FORCEADD CAD_NOTE..1
(-1250 2850);
FORCEPROP 0 LAST L1 PLACE PU RES CLOSE TO FLASH IC
J 0
(-2100 2725);
DISPLAY 0.851064 (-2100 2725);
PAINT GREEN (-2100 2725);
FORCEPROP 2 LAST CDS_LIB logical_power
J 0
(-1250 2850);
DISPLAY INVISIBLE (-1250 2850);
FORCEPROP 1 LAST COMMENT_BODY TRUE
J 0
(-1225 2950);
DISPLAY 0.978723 (-1225 2950);
PAINT PEACH (-1225 2950);
DISPLAY INVISIBLE (-1225 2950);
FORCEADD BOM_NOTE..1
(900 3100);
FORCEPROP 0 LAST L3 512MBIT(64MBYTE)
J 0
(750 2775);
DISPLAY 1.021277 (750 2775);
PAINT GREEN (750 2775);
FORCEPROP 0 LAST L1 FLASH PN: AKE3FF00Z00(MX25L51245GMI-10G) SOIC16
J 0
(750 2875);
DISPLAY 1.021277 (750 2875);
PAINT GREEN (750 2875);
FORCEPROP 0 LAST L2 SOCKET PN: DG016000006
J 0
(750 2975);
DISPLAY 1.021277 (750 2975);
PAINT GREEN (750 2975);
FORCEPROP 2 LAST CDS_LIB logical_power
J 0
(900 3100);
PAINT MONO (900 3100);
DISPLAY INVISIBLE (900 3100);
FORCEPROP 1 LAST COMMENT_BODY TRUE
J 0
(925 3200);
DISPLAY 0.978723 (925 3200);
PAINT PEACH (925 3200);
DISPLAY INVISIBLE (925 3200);
FORCEADD CAD_NOTE..1
(-1250 3100);
FORCEPROP 0 LAST L1 PLACE CAP CLOSE TO PIN VCC
J 0
(-2100 2950);
DISPLAY 0.872340 (-2100 2950);
PAINT GREEN (-2100 2950);
FORCEPROP 2 LAST CDS_LIB logical_power
J 0
(-1250 3100);
DISPLAY INVISIBLE (-1250 3100);
FORCEPROP 1 LAST COMMENT_BODY TRUE
J 0
(-1225 3200);
DISPLAY 0.978723 (-1225 3200);
PAINT PEACH (-1225 3200);
DISPLAY INVISIBLE (-1225 3200);
FORCEADD DNS..1
(3275 2225);
PAINT RED (3275 2225);
FORCEPROP 2 LAST CDS_LIB mstr_misc
J 0
(3275 2225);
DISPLAY INVISIBLE (3275 2225);
FORCEPROP 1 LAST COMMENT_BODY TRUE
R 1
J 0
(3350 2000);
DISPLAY 0.872340 (3350 2000);
PAINT PEACH (3350 2000);
DISPLAY INVISIBLE (3350 2000);
FORCEADD DNS..1
(1300 775);
PAINT RED (1300 775);
FORCEPROP 2 LAST CDS_LIB mstr_misc
J 0
(1300 775);
DISPLAY INVISIBLE (1300 775);
FORCEPROP 1 LAST COMMENT_BODY TRUE
R 1
J 0
(1375 550);
DISPLAY 0.872340 (1375 550);
PAINT PEACH (1375 550);
DISPLAY INVISIBLE (1375 550);
WIRE 16 -1 (875 1150)(875 1025);
WIRE 16 -1 (50 3200)(50 3250);
WIRE 16 -1 (-350 3200)(50 3200);
WIRE 16 -1 (50 3200)(50 2675);
WIRE 16 -1 (3275 2450)(3275 2350);
WIRE 16 -1 (1750 475)(1825 475);
WIRE 16 -1 (1825 1850)(1900 1850);
WIRE 16 -1 (-800 2925)(-800 2875);
WIRE 16 -1 (-350 2925)(-350 2875);
WIRE 16 -1 (-725 1450)(-725 1325);
WIRE 16 -1 (875 1025)(900 1025);
WIRE 16 -1 (-1075 2250)(-1075 2000);
WIRE 16 -1 (-1475 2000)(-1075 2000);
WIRE 16 -1 (450 625)(900 625);
WIRE 16 -1 (450 2000)(875 2000);
WIRE 16 -1 (450 2000)(-1075 2000);
FORCEPROP 2 LAST SIG_NAME SPI_PCH_IO2_FLASH_R1
J 0
(-535 2010);
DISPLAY 0.808511 (-535 2010);
WIRE 16 -1 (450 2000)(450 625);
WIRE 16 -1 (525 675)(900 675);
WIRE 16 -1 (525 2050)(-1475 2050);
FORCEPROP 2 LAST SIG_NAME SPI_PCH_IO0_FLASH_R1
J 0
(-535 2060);
DISPLAY 0.808511 (-535 2060);
WIRE 16 -1 (875 2050)(525 2050);
WIRE 16 -1 (525 2050)(525 675);
WIRE 16 -1 (625 725)(900 725);
WIRE 16 -1 (625 2100)(-1475 2100);
FORCEPROP 2 LAST SIG_NAME SPI_PCH_CLK_FLASH_R1
J 0
(-535 2110);
DISPLAY 0.808511 (-535 2110);
WIRE 16 -1 (875 2100)(625 2100);
WIRE 16 -1 (625 2100)(625 725);
WIRE 16 -1 (3275 2150)(3275 1950);
WIRE 16 -1 (2375 625)(1750 625);
WIRE 16 -1 (3275 1950)(2375 1950);
WIRE 16 -1 (1825 1950)(2375 1950);
FORCEPROP 2 LAST SIG_NAME RST_SPI_PCH_FLASH_R1_N
J 0
(1915 1960);
DISPLAY 0.808511 (1915 1960);
WIRE 16 -1 (2375 1950)(2375 625);
WIRE 16 -1 (1750 1025)(2275 1025);
FORCEPROP 2 LAST SIG_NAME TP_J40_4
J 0
(1915 1035);
DISPLAY 0.808511 (1915 1035);
PAINT WHITE (1915 1035);
FORCEPROP 2 LASTPROP $XR0 45 
J 0
(2305 1025);
DISPLAY 0.638298 (2305 1025);
PAINT MONO (2305 1025);
WIRE 16 -1 (1750 975)(2275 975);
FORCEPROP 2 LAST SIG_NAME TP_J40_13
J 0
(1915 985);
DISPLAY 0.808511 (1915 985);
PAINT WHITE (1915 985);
FORCEPROP 2 LASTPROP $XR0 45 
J 0
(2305 975);
DISPLAY 0.638298 (2305 975);
PAINT MONO (2305 975);
WIRE 16 -1 (1750 925)(2275 925);
FORCEPROP 2 LAST SIG_NAME TP_J40_14
J 0
(1915 935);
DISPLAY 0.808511 (1915 935);
PAINT WHITE (1915 935);
FORCEPROP 2 LASTPROP $XR0 45 
J 0
(2305 925);
DISPLAY 0.638298 (2305 925);
PAINT MONO (2305 925);
WIRE 16 -1 (1750 875)(2275 875);
FORCEPROP 2 LAST SIG_NAME TP_J40_5
J 0
(1915 885);
DISPLAY 0.808511 (1915 885);
PAINT WHITE (1915 885);
FORCEPROP 2 LASTPROP $XR0 45 
J 0
(2305 875);
DISPLAY 0.638298 (2305 875);
PAINT MONO (2305 875);
WIRE 16 -1 (1750 825)(2275 825);
FORCEPROP 2 LAST SIG_NAME TP_J40_6
J 0
(1915 835);
DISPLAY 0.808511 (1915 835);
PAINT WHITE (1915 835);
FORCEPROP 2 LASTPROP $XR0 45 
J 0
(2305 825);
DISPLAY 0.638298 (2305 825);
PAINT MONO (2305 825);
WIRE 16 -1 (400 575)(900 575);
WIRE 16 -1 (400 1950)(-1475 1950);
FORCEPROP 2 LAST SIG_NAME SPI_PCH_IO1_FLASH_R1
J 0
(-535 1960);
DISPLAY 0.808511 (-535 1960);
WIRE 16 -1 (875 1950)(400 1950);
WIRE 16 -1 (400 1950)(400 575);
WIRE 16 -1 (-1475 1900)(-850 1900);
WIRE 16 -1 (-850 2250)(-850 1900);
FORCEPROP 2 LAST SIG_NAME SPI_PCH_CS0_FLASH_R1_N
J 0
(-535 1910);
DISPLAY 0.808511 (-535 1910);
WIRE 16 -1 (-850 1900)(-725 1900);
WIRE 16 -1 (-725 1650)(-725 1900);
WIRE 16 -1 (350 525)(900 525);
WIRE 16 -1 (350 1900)(-725 1900);
WIRE 16 -1 (875 1900)(350 1900);
WIRE 16 -1 (350 1900)(350 525);
WIRE 16 -1 (-625 1850)(-1475 1850);
WIRE 16 -1 (-625 2250)(-625 1850);
WIRE 16 -1 (275 475)(900 475);
WIRE 16 -1 (275 1850)(875 1850);
WIRE 16 -1 (275 1850)(-625 1850);
FORCEPROP 2 LAST SIG_NAME SPI_PCH_IO3_FLASH_R1
J 0
(-535 1860);
DISPLAY 0.808511 (-535 1860);
WIRE 16 -1 (275 1850)(275 475);
WIRE 16 -1 (-1075 2675)(-1075 2450);
WIRE 16 -1 (-1075 2675)(-850 2675);
WIRE 16 -1 (-850 2675)(-850 2450);
WIRE 16 -1 (50 2250)(875 2250);
WIRE 16 -1 (-625 2675)(-625 2450);
WIRE 16 -1 (-625 2675)(-850 2675);
WIRE 16 -1 (50 2675)(-625 2675);
WIRE 16 -1 (50 2675)(50 2250);
WIRE 16 -1 (-350 3125)(-350 3200);
WIRE 16 -1 (-800 3200)(-800 3125);
WIRE 16 -1 (-800 3200)(-350 3200);
WIRE 16 -1 (1825 2000)(2575 2000);
FORCEPROP 2 LAST SIG_NAME TP_J40_4
J 0
(1990 2010);
DISPLAY 0.808511 (1990 2010);
PAINT WHITE (1990 2010);
FORCEPROP 2 LASTPROP $XR0 45 
J 0
(2600 2000);
DISPLAY 0.638298 (2600 2000);
PAINT MONO (2600 2000);
WIRE 16 -1 (1750 725)(2275 725);
FORCEPROP 2 LAST SIG_NAME TP_J40_12
J 0
(1915 735);
DISPLAY 0.808511 (1915 735);
PAINT WHITE (1915 735);
FORCEPROP 2 LASTPROP $XR0 45 
J 0
(2305 725);
DISPLAY 0.638298 (2305 725);
PAINT MONO (2305 725);
WIRE 16 -1 (1825 2250)(2575 2250);
FORCEPROP 2 LAST SIG_NAME TP_J40_13
J 0
(1990 2260);
DISPLAY 0.808511 (1990 2260);
PAINT WHITE (1990 2260);
FORCEPROP 2 LASTPROP $XR0 45 
J 0
(2605 2250);
DISPLAY 0.638298 (2605 2250);
PAINT MONO (2605 2250);
WIRE 16 -1 (1825 2300)(2575 2300);
FORCEPROP 2 LAST SIG_NAME TP_J40_14
J 0
(1990 2310);
DISPLAY 0.808511 (1990 2310);
PAINT WHITE (1990 2310);
FORCEPROP 2 LASTPROP $XR0 45 
J 0
(2605 2300);
DISPLAY 0.638298 (2605 2300);
PAINT MONO (2605 2300);
WIRE 16 -1 (1825 2200)(2575 2200);
FORCEPROP 2 LAST SIG_NAME TP_J40_12
J 0
(1990 2210);
DISPLAY 0.808511 (1990 2210);
PAINT WHITE (1990 2210);
FORCEPROP 2 LASTPROP $XR0 45 
J 0
(2605 2200);
DISPLAY 0.638298 (2605 2200);
PAINT MONO (2605 2200);
WIRE 16 -1 (1825 2100)(2575 2100);
FORCEPROP 2 LAST SIG_NAME TP_J40_6
J 0
(1990 2110);
DISPLAY 0.808511 (1990 2110);
PAINT WHITE (1990 2110);
FORCEPROP 2 LASTPROP $XR0 45 
J 0
(2605 2100);
DISPLAY 0.638298 (2605 2100);
PAINT MONO (2605 2100);
WIRE 16 -1 (1825 2050)(2575 2050);
FORCEPROP 2 LAST SIG_NAME TP_J40_5
J 0
(1990 2060);
DISPLAY 0.808511 (1990 2060);
PAINT WHITE (1990 2060);
FORCEPROP 2 LASTPROP $XR0 45 
J 0
(2605 2050);
DISPLAY 0.638298 (2605 2050);
PAINT MONO (2605 2050);
WIRE 16 -1 (-1675 2000)(-2825 2000);
FORCEPROP 2 LAST SIG_NAME SPI_PCH_MUXED_IO2
J 0
(-2675 2010);
DISPLAY 0.808511 (-2675 2010);
WIRE 16 -1 (-2850 1900)(-1675 1900);
FORCEPROP 2 LAST SIG_NAME SPI_PCH_MUXED_CS0_N
J 0
(-2675 1910);
DISPLAY 0.808511 (-2675 1910);
WIRE 16 -1 (-1675 1850)(-2825 1850);
FORCEPROP 2 LAST SIG_NAME SPI_PCH_MUXED_IO3
J 0
(-2675 1860);
DISPLAY 0.808511 (-2675 1860);
WIRE 16 -1 (-1675 1950)(-2825 1950);
FORCEPROP 2 LAST SIG_NAME SPI_PCH_MUXED_IO1
J 0
(-2675 1960);
DISPLAY 0.808511 (-2675 1960);
WIRE 16 -1 (-1675 2050)(-2825 2050);
FORCEPROP 2 LAST SIG_NAME SPI_PCH_MUXED_IO0
J 0
(-2675 2060);
DISPLAY 0.808511 (-2675 2060);
WIRE 16 -1 (-2850 2100)(-1675 2100);
FORCEPROP 2 LAST SIG_NAME SPI_PCH_MUXED_CLK
J 0
(-2675 2110);
DISPLAY 0.808511 (-2675 2110);
WIRE 16 -1 (1750 775)(2275 775);
FORCEPROP 2 LAST SIG_NAME TP_J40_11
J 0
(1915 785);
DISPLAY 0.808511 (1915 785);
PAINT WHITE (1915 785);
FORCEPROP 2 LASTPROP $XR0 45 
J 0
(2305 775);
DISPLAY 0.638298 (2305 775);
PAINT MONO (2305 775);
WIRE 16 -1 (1825 2150)(2575 2150);
FORCEPROP 2 LAST SIG_NAME TP_J40_11
J 0
(1990 2160);
DISPLAY 0.808511 (1990 2160);
PAINT WHITE (1990 2160);
FORCEPROP 2 LASTPROP $XR0 45 
J 0
(2605 2150);
DISPLAY 0.638298 (2605 2150);
PAINT MONO (2605 2150);
DOT 1 (-725 1900);
DOT 1 (50 3200);
DOT 1 (-350 3200);
DOT 1 (625 2100);
DOT 1 (450 2000);
DOT 1 (400 1950);
DOT 1 (350 1900);
DOT 1 (275 1850);
DOT 1 (2375 1950);
DOT 1 (-1075 2000);
DOT 1 (-850 2675);
DOT 1 (-850 1900);
DOT 1 (-625 2675);
DOT 1 (-625 1850);
DOT 1 (50 2675);
DOT 1 (525 2050);
FORCENOTE
NOTE:BIOS ROM HAS THE INTERNAL PU FOR PIN3
(2400 1825) 0;
DISPLAY LEFT (2400 1825);
DISPLAY 1.021277 (2400 1825);
QUIT
